(kicad_pcb
	(version 20260206)
	(generator "pcbnew")
	(generator_version "10.0")
	(general
		(thickness 1.6)
		(legacy_teardrops no)
	)
	(paper "A4")
	(title_block
		(title "01162023_DA0F0TEBIF0_F0T_Expander_BD_F_brd_V02_OCP.brd")
		(comment 1 "Grand Teton / footprints 5395-5401 of 9728")
	)
	(layers
		(0 "F.Cu" signal "TOP")
		(4 "In1.Cu" signal "GND")
		(6 "In2.Cu" signal "VCC")
		(8 "In3.Cu" signal "VCC1")
		(10 "In4.Cu" signal "GND1")
		(12 "In5.Cu" signal "IN1")
		(14 "In6.Cu" signal "GND2")
		(16 "In7.Cu" signal "IN2")
		(18 "In8.Cu" signal "GND3")
		(20 "In9.Cu" signal "IN3")
		(22 "In10.Cu" signal "GND4")
		(24 "In11.Cu" signal "IN4")
		(26 "In12.Cu" signal "GND5")
		(28 "In13.Cu" signal "IN5")
		(30 "In14.Cu" signal "GND6")
		(32 "In15.Cu" signal "IN6")
		(34 "In16.Cu" signal "GND7")
		(2 "B.Cu" signal "BOTTOM")
		(9 "F.Adhes" user "F.Adhesive")
		(11 "B.Adhes" user "B.Adhesive")
		(13 "F.Paste" user "Package Geometry/Pastemask Top")
		(15 "B.Paste" user "Package Geometry/Pastemask Bottom")
		(5 "F.SilkS" user "Ref Des/Silkscreen Top")
		(7 "B.SilkS" user "Ref Des/Silkscreen Bottom")
		(1 "F.Mask" user "Board Geometry/Soldermask Top")
		(3 "B.Mask" user "Board Geometry/Soldermask Bottom")
		(17 "Dwgs.User" user "User.Drawings")
		(19 "Cmts.User" user "User.Comments")
		(21 "Eco1.User" user "User.Eco1")
		(23 "Eco2.User" user "User.Eco2")
		(25 "Edge.Cuts" user "Board Geometry/Outline")
		(27 "Margin" user)
		(31 "F.CrtYd" user "Package Geometry/Place Bound Top")
		(29 "B.CrtYd" user "Package Geometry/Place Bound Bottom")
		(35 "F.Fab" user "Ref Des/Assembly Top")
		(33 "B.Fab" user "Ref Des/Assembly Bottom")
	)
	(footprint ""
		(layer "F.Cu")
		(at 400.369024 8.149844)
		(property "Reference" "DE15T_2"
			(at -3.6068 -2.962148 0)
			(unlocked yes)
			(layer "F.SilkS")
			(effects
				(font
					(size 0.7874 0.5842)
					(thickness 0.1524)
				)
				(justify left)
			)
		)
		(property "Value" ""
			(at 0 0 0)
			(layer "F.Fab")
			(effects
				(font
					(size 1.27 1.27)
				)
			)
		)
		(duplicate_pad_numbers_are_jumpers no)
		(fp_line
			(start -1.2192 -2.1082)
			(end 1.2192 -2.1082)
			(stroke
				(width 0.1524)
				(type default)
			)
			(layer "F.SilkS")
		)
		(fp_line
			(start -1.2192 2.1082)
			(end -1.2192 -2.1082)
			(stroke
				(width 0.1524)
				(type default)
			)
			(layer "F.SilkS")
		)
		(fp_line
			(start 1.2192 -2.1082)
			(end 1.2192 2.1082)
			(stroke
				(width 0.1524)
				(type default)
			)
			(layer "F.SilkS")
		)
		(fp_line
			(start 1.2192 2.1082)
			(end -1.2192 2.1082)
			(stroke
				(width 0.1524)
				(type default)
			)
			(layer "F.SilkS")
		)
		(pad "" np_thru_hole circle
			(at -2.8829 -1.27 270)
			(size 1.0414 1.0414)
			(drill 1.0414)
			(layers "*.Cu" "*.Mask")
			(clearance 0.381)
			(thermal_gap 0.381)
		)
		(pad "" np_thru_hole circle
			(at -2.8829 1.27 270)
			(size 1.0414 1.0414)
			(drill 1.0414)
			(layers "*.Cu" "*.Mask")
			(clearance 0.381)
			(thermal_gap 0.381)
		)
		(pad "" np_thru_hole circle
			(at 3.4671 -1.27 270)
			(size 1.0414 1.0414)
			(drill 1.0414)
			(layers "*.Cu" "*.Mask")
			(clearance 0.381)
			(thermal_gap 0.381)
		)
		(pad "" np_thru_hole circle
			(at 3.4671 1.27 270)
			(size 1.0414 1.0414)
			(drill 1.0414)
			(layers "*.Cu" "*.Mask")
			(clearance 0.381)
			(thermal_gap 0.381)
		)
		(pad "1" smd rect
			(at 0.8255 -0.249936 270)
			(size 0.3048 0.508)
			(layers "F.Cu" "F.Mask" "F.Paste")
			(net "85_10INCH_IN3_DN")
		)
		(pad "2" smd rect
			(at 0.8255 0.249936 270)
			(size 0.3048 0.508)
			(layers "F.Cu" "F.Mask" "F.Paste")
			(net "85_10INCH_IN3_DP")
		)
		(pad "3" smd circle
			(at 0 0)
			(size 0 0)
			(layers "F.Cu" "F.Mask" "F.Paste")
			(net "COUPON_GND2")
		)
		(zone
			(layer "F.Cu")
			(hatch none 0.5)
			(connect_pads
				(clearance 0)
			)
			(min_thickness 0.25)
			(keepout
				(tracks not_allowed)
				(vias allowed)
				(pads allowed)
				(copperpour not_allowed)
				(footprints allowed)
			)
			(placement
				(enabled no)
				(sheetname "")
			)
			(fill
				(thermal_gap 0.5)
				(thermal_bridge_width 0.5)
				(island_removal_mode 0)
			)
			(polygon
				(pts
					(xy 401.486624 7.601204) (xy 401.486624 7.696708) (xy 400.889724 7.696708) (xy 400.889724 8.103108)
					(xy 401.486624 8.103108) (xy 401.486624 8.19658) (xy 400.889724 8.19658) (xy 400.889724 8.60298)
					(xy 401.486624 8.60298) (xy 401.486624 8.698484) (xy 400.788124 8.698484) (xy 400.788124 7.601204)
				)
			)
		)
		(zone
			(layers "F.Cu" "B.Cu" "In1.Cu" "In2.Cu" "In3.Cu" "In4.Cu" "In5.Cu" "In6.Cu"
				"In7.Cu" "In8.Cu" "In9.Cu" "In10.Cu" "In11.Cu" "In12.Cu" "In13.Cu" "In14.Cu"
				"In15.Cu" "In16.Cu"
			)
			(hatch none 0.5)
			(connect_pads
				(clearance 0)
			)
			(min_thickness 0.25)
			(keepout
				(tracks not_allowed)
				(vias allowed)
				(pads allowed)
				(copperpour not_allowed)
				(footprints allowed)
			)
			(placement
				(enabled no)
				(sheetname "")
			)
			(fill
				(thermal_gap 0.5)
				(thermal_bridge_width 0.5)
				(island_removal_mode 0)
			)
			(polygon
				(pts
					(arc
						(start 398.413224 6.879844)
						(mid 396.559024 6.879844)
						(end 398.413224 6.879844)
					)
				)
			)
		)
		(zone
			(layers "F.Cu" "B.Cu" "In1.Cu" "In2.Cu" "In3.Cu" "In4.Cu" "In5.Cu" "In6.Cu"
				"In7.Cu" "In8.Cu" "In9.Cu" "In10.Cu" "In11.Cu" "In12.Cu" "In13.Cu" "In14.Cu"
				"In15.Cu" "In16.Cu"
			)
			(hatch none 0.5)
			(connect_pads
				(clearance 0)
			)
			(min_thickness 0.25)
			(keepout
				(tracks not_allowed)
				(vias allowed)
				(pads allowed)
				(copperpour not_allowed)
				(footprints allowed)
			)
			(placement
				(enabled no)
				(sheetname "")
			)
			(fill
				(thermal_gap 0.5)
				(thermal_bridge_width 0.5)
				(island_removal_mode 0)
			)
			(polygon
				(pts
					(arc
						(start 398.413224 9.419844)
						(mid 396.559024 9.419844)
						(end 398.413224 9.419844)
					)
				)
			)
		)
		(zone
			(layers "F.Cu" "B.Cu" "In1.Cu" "In2.Cu" "In3.Cu" "In4.Cu" "In5.Cu" "In6.Cu"
				"In7.Cu" "In8.Cu" "In9.Cu" "In10.Cu" "In11.Cu" "In12.Cu" "In13.Cu" "In14.Cu"
				"In15.Cu" "In16.Cu"
			)
			(hatch none 0.5)
			(connect_pads
				(clearance 0)
			)
			(min_thickness 0.25)
			(keepout
				(tracks not_allowed)
				(vias allowed)
				(pads allowed)
				(copperpour not_allowed)
				(footprints allowed)
			)
			(placement
				(enabled no)
				(sheetname "")
			)
			(fill
				(thermal_gap 0.5)
				(thermal_bridge_width 0.5)
				(island_removal_mode 0)
			)
			(polygon
				(pts
					(arc
						(start 404.763224 6.879844)
						(mid 402.909024 6.879844)
						(end 404.763224 6.879844)
					)
				)
			)
		)
		(zone
			(layers "F.Cu" "B.Cu" "In1.Cu" "In2.Cu" "In3.Cu" "In4.Cu" "In5.Cu" "In6.Cu"
				"In7.Cu" "In8.Cu" "In9.Cu" "In10.Cu" "In11.Cu" "In12.Cu" "In13.Cu" "In14.Cu"
				"In15.Cu" "In16.Cu"
			)
			(hatch none 0.5)
			(connect_pads
				(clearance 0)
			)
			(min_thickness 0.25)
			(keepout
				(tracks not_allowed)
				(vias allowed)
				(pads allowed)
				(copperpour not_allowed)
				(footprints allowed)
			)
			(placement
				(enabled no)
				(sheetname "")
			)
			(fill
				(thermal_gap 0.5)
				(thermal_bridge_width 0.5)
				(island_removal_mode 0)
			)
			(polygon
				(pts
					(arc
						(start 404.763224 9.419844)
						(mid 402.909024 9.419844)
						(end 404.763224 9.419844)
					)
				)
			)
		)
	)
	(footprint ""
		(layer "F.Cu")
		(at 374.567958 -53.051456)
		(property "Reference" "R4467"
			(at 0 0 0)
			(layer "F.SilkS")
			(hide yes)
			(effects
				(font
					(size 1.27 1.27)
				)
			)
		)
		(property "Value" ""
			(at 0 0 0)
			(layer "F.Fab")
			(effects
				(font
					(size 1.27 1.27)
				)
			)
		)
		(duplicate_pad_numbers_are_jumpers no)
		(fp_line
			(start -0.7874 -0.4064)
			(end 0.7874 -0.4064)
			(stroke
				(width 0.1524)
				(type default)
			)
			(layer "F.SilkS")
		)
		(fp_line
			(start -0.7874 0.4064)
			(end -0.7874 -0.4064)
			(stroke
				(width 0.1524)
				(type default)
			)
			(layer "F.SilkS")
		)
		(fp_line
			(start 0.7874 -0.4064)
			(end 0.7874 0.4064)
			(stroke
				(width 0.1524)
				(type default)
			)
			(layer "F.SilkS")
		)
		(fp_line
			(start 0.7874 0.4064)
			(end -0.7874 0.4064)
			(stroke
				(width 0.1524)
				(type default)
			)
			(layer "F.SilkS")
		)
		(fp_line
			(start -0.67945 -0.305054)
			(end -0.12065 -0.305054)
			(stroke
				(width 0.1)
				(type default)
			)
			(layer "F.Fab")
		)
		(fp_line
			(start -0.67945 0.3048)
			(end -0.67945 -0.305054)
			(stroke
				(width 0.1)
				(type default)
			)
			(layer "F.Fab")
		)
		(fp_line
			(start -0.12065 -0.305054)
			(end -0.12065 -0.2794)
			(stroke
				(width 0.1)
				(type default)
			)
			(layer "F.Fab")
		)
		(fp_line
			(start -0.12065 -0.2794)
			(end 0.12065 -0.2794)
			(stroke
				(width 0.1)
				(type default)
			)
			(layer "F.Fab")
		)
		(fp_line
			(start -0.12065 0.2794)
			(end -0.12065 0.3048)
			(stroke
				(width 0.1)
				(type default)
			)
			(layer "F.Fab")
		)
		(fp_line
			(start -0.12065 0.3048)
			(end -0.67945 0.3048)
			(stroke
				(width 0.1)
				(type default)
			)
			(layer "F.Fab")
		)
		(fp_line
			(start 0.120396 0.2794)
			(end -0.12065 0.2794)
			(stroke
				(width 0.1)
				(type default)
			)
			(layer "F.Fab")
		)
		(fp_line
			(start 0.120396 0.3048)
			(end 0.120396 0.2794)
			(stroke
				(width 0.1)
				(type default)
			)
			(layer "F.Fab")
		)
		(fp_line
			(start 0.12065 -0.3048)
			(end 0.67945 -0.3048)
			(stroke
				(width 0.1)
				(type default)
			)
			(layer "F.Fab")
		)
		(fp_line
			(start 0.12065 -0.2794)
			(end 0.12065 -0.3048)
			(stroke
				(width 0.1)
				(type default)
			)
			(layer "F.Fab")
		)
		(fp_line
			(start 0.67945 -0.3048)
			(end 0.67945 0.3048)
			(stroke
				(width 0.1)
				(type default)
			)
			(layer "F.Fab")
		)
		(fp_line
			(start 0.67945 0.3048)
			(end 0.120396 0.3048)
			(stroke
				(width 0.1)
				(type default)
			)
			(layer "F.Fab")
		)
		(pad "1" smd circle
			(at -0.40005 0)
			(size 0 0)
			(layers "F.Cu" "F.Mask" "F.Paste")
			(net "PWRGD_P12V_SSD12")
		)
		(pad "2" smd circle
			(at 0.40005 0)
			(size 0 0)
			(layers "F.Cu" "F.Mask" "F.Paste")
			(net "PWRGD_P12V_SSD12_R")
		)
	)
	(footprint ""
		(layer "F.Cu")
		(at 299.875702 -356.244906 90)
		(property "Reference" "C2372"
			(at 0 0 90)
			(layer "F.SilkS")
			(hide yes)
			(effects
				(font
					(size 1.27 1.27)
				)
			)
		)
		(property "Value" ""
			(at 0 0 90)
			(layer "F.Fab")
			(effects
				(font
					(size 1.27 1.27)
				)
			)
		)
		(duplicate_pad_numbers_are_jumpers no)
		(fp_line
			(start 0.299974 -0.150114)
			(end 0.299974 0.150114)
			(stroke
				(width 0.1)
				(type default)
			)
			(layer "F.Fab")
		)
		(fp_line
			(start -0.299974 -0.150114)
			(end 0.299974 -0.150114)
			(stroke
				(width 0.1)
				(type default)
			)
			(layer "F.Fab")
		)
		(fp_line
			(start 0.299974 0.150114)
			(end -0.299974 0.150114)
			(stroke
				(width 0.1)
				(type default)
			)
			(layer "F.Fab")
		)
		(fp_line
			(start -0.299974 0.150114)
			(end -0.299974 -0.150114)
			(stroke
				(width 0.1)
				(type default)
			)
			(layer "F.Fab")
		)
		(pad "1" smd rect
			(at -0.2667 0 90)
			(size 0.3048 0.381)
			(layers "F.Cu" "F.Mask" "F.Paste")
			(net "P5E_PEX2_STN4_TX_DN<64>")
		)
		(pad "2" smd rect
			(at 0.2667 0 90)
			(size 0.3048 0.381)
			(layers "F.Cu" "F.Mask" "F.Paste")
			(net "P5E_PEX2_STN4_TX_C_DN<64>")
		)
	)
	(footprint ""
		(layer "F.Cu")
		(at 465.710524 -555.054008 90)
		(property "Reference" "HS_BP0"
			(at -0.5842 -1.31953 90)
			(unlocked yes)
			(layer "B.SilkS")
			(effects
				(font
					(size 0.7874 0.5842)
					(thickness 0.1524)
				)
				(justify left mirror)
			)
		)
		(property "Value" ""
			(at 0 0 90)
			(layer "F.Fab")
			(effects
				(font
					(size 1.27 1.27)
				)
			)
		)
		(duplicate_pad_numbers_are_jumpers no)
		(pad "1" thru_hole circle
			(at 0 0 90)
			(size 0.4572 0.4572)
			(drill 0.2032)
			(layers "*.Cu" "*.Mask")
			(remove_unused_layers no)
			(net "Net_9202")
			(clearance 0.127)
			(thermal_gap 0.127)
			(padstack
				(mode front_inner_back)
				(layer "Inner"
					(shape circle)
					(size 0.4572 0.4572)
					(clearance 0.127)
				)
				(layer "B.Cu"
					(shape circle)
					(size 0.508 0.508)
					(clearance 0.1016)
				)
			)
		)
	)
	(footprint ""
		(layer "F.Cu")
		(at 196.119242 -153.390346 180)
		(property "Reference" "C215"
			(at 0 0 180)
			(layer "F.SilkS")
			(hide yes)
			(effects
				(font
					(size 1.27 1.27)
				)
			)
		)
		(property "Value" ""
			(at 0 0 180)
			(layer "F.Fab")
			(effects
				(font
					(size 1.27 1.27)
				)
			)
		)
		(duplicate_pad_numbers_are_jumpers no)
		(fp_line
			(start 0.299974 0.150114)
			(end -0.299974 0.150114)
			(stroke
				(width 0.1)
				(type default)
			)
			(layer "F.Fab")
		)
		(fp_line
			(start 0.299974 -0.150114)
			(end 0.299974 0.150114)
			(stroke
				(width 0.1)
				(type default)
			)
			(layer "F.Fab")
		)
		(fp_line
			(start -0.299974 0.150114)
			(end -0.299974 -0.150114)
			(stroke
				(width 0.1)
				(type default)
			)
			(layer "F.Fab")
		)
		(fp_line
			(start -0.299974 -0.150114)
			(end 0.299974 -0.150114)
			(stroke
				(width 0.1)
				(type default)
			)
			(layer "F.Fab")
		)
		(pad "1" smd rect
			(at -0.2667 0 180)
			(size 0.3048 0.381)
			(layers "F.Cu" "F.Mask" "F.Paste")
			(net "P5E_PEX1_STN0_TX_DP<14>")
		)
		(pad "2" smd rect
			(at 0.2667 0 180)
			(size 0.3048 0.381)
			(layers "F.Cu" "F.Mask" "F.Paste")
			(net "P5E_PEX1_STN0_TX_C_DP<14>")
		)
	)
	(footprint ""
		(layer "F.Cu")
		(at 233.949494 -180.68163 -90)
		(property "Reference" "R5492"
			(at 0 0 270)
			(layer "F.SilkS")
			(hide yes)
			(effects
				(font
					(size 1.27 1.27)
				)
			)
		)
		(property "Value" ""
			(at 0 0 270)
			(layer "F.Fab")
			(effects
				(font
					(size 1.27 1.27)
				)
			)
		)
		(duplicate_pad_numbers_are_jumpers no)
		(fp_line
			(start -0.7874 0.4064)
			(end -0.7874 -0.4064)
			(stroke
				(width 0.1524)
				(type default)
			)
			(layer "F.SilkS")
		)
		(fp_line
			(start 0.7874 0.4064)
			(end -0.7874 0.4064)
			(stroke
				(width 0.1524)
				(type default)
			)
			(layer "F.SilkS")
		)
		(fp_line
			(start -0.7874 -0.4064)
			(end 0.7874 -0.4064)
			(stroke
				(width 0.1524)
				(type default)
			)
			(layer "F.SilkS")
		)
		(fp_line
			(start 0.7874 -0.4064)
			(end 0.7874 0.4064)
			(stroke
				(width 0.1524)
				(type default)
			)
			(layer "F.SilkS")
		)
		(fp_line
			(start -0.67945 0.3048)
			(end -0.67945 -0.305054)
			(stroke
				(width 0.1)
				(type default)
			)
			(layer "F.Fab")
		)
		(fp_line
			(start -0.12065 0.3048)
			(end -0.67945 0.3048)
			(stroke
				(width 0.1)
				(type default)
			)
			(layer "F.Fab")
		)
		(fp_line
			(start 0.120396 0.3048)
			(end 0.120396 0.2794)
			(stroke
				(width 0.1)
				(type default)
			)
			(layer "F.Fab")
		)
		(fp_line
			(start 0.67945 0.3048)
			(end 0.120396 0.3048)
			(stroke
				(width 0.1)
				(type default)
			)
			(layer "F.Fab")
		)
		(fp_line
			(start -0.12065 0.2794)
			(end -0.12065 0.3048)
			(stroke
				(width 0.1)
				(type default)
			)
			(layer "F.Fab")
		)
		(fp_line
			(start 0.120396 0.2794)
			(end -0.12065 0.2794)
			(stroke
				(width 0.1)
				(type default)
			)
			(layer "F.Fab")
		)
		(fp_line
			(start -0.12065 -0.2794)
			(end 0.12065 -0.2794)
			(stroke
				(width 0.1)
				(type default)
			)
			(layer "F.Fab")
		)
		(fp_line
			(start 0.12065 -0.2794)
			(end 0.12065 -0.3048)
			(stroke
				(width 0.1)
				(type default)
			)
			(layer "F.Fab")
		)
		(fp_line
			(start 0.12065 -0.3048)
			(end 0.67945 -0.3048)
			(stroke
				(width 0.1)
				(type default)
			)
			(layer "F.Fab")
		)
		(fp_line
			(start 0.67945 -0.3048)
			(end 0.67945 0.3048)
			(stroke
				(width 0.1)
				(type default)
			)
			(layer "F.Fab")
		)
		(fp_line
			(start -0.67945 -0.305054)
			(end -0.12065 -0.305054)
			(stroke
				(width 0.1)
				(type default)
			)
			(layer "F.Fab")
		)
		(fp_line
			(start -0.12065 -0.305054)
			(end -0.12065 -0.2794)
			(stroke
				(width 0.1)
				(type default)
			)
			(layer "F.Fab")
		)
		(pad "1" smd circle
			(at -0.40005 0 270)
			(size 0 0)
			(layers "F.Cu" "F.Mask" "F.Paste")
			(net "P3V3_AUX")
		)
		(pad "2" smd circle
			(at 0.40005 0 270)
			(size 0 0)
			(layers "F.Cu" "F.Mask" "F.Paste")
			(net "RST_BIC_EXTRST_R_N")
		)
	)
	(footprint ""
		(layer "F.Cu")
		(at 325.925942 -125.530864)
		(property "Reference" "PC487"
			(at 0 0 0)
			(layer "F.SilkS")
			(hide yes)
			(effects
				(font
					(size 1.27 1.27)
				)
			)
		)
		(property "Value" ""
			(at 0 0 0)
			(layer "F.Fab")
			(effects
				(font
					(size 1.27 1.27)
				)
			)
		)
		(duplicate_pad_numbers_are_jumpers no)
		(fp_line
			(start -1.524 -0.762)
			(end 1.524 -0.762)
			(stroke
				(width 0.1524)
				(type default)
			)
			(layer "F.SilkS")
		)
		(fp_line
			(start -1.524 0.762)
			(end -1.524 -0.762)
			(stroke
				(width 0.1524)
				(type default)
			)
			(layer "F.SilkS")
		)
		(fp_line
			(start 1.524 -0.762)
			(end 1.524 0.762)
			(stroke
				(width 0.1524)
				(type default)
			)
			(layer "F.SilkS")
		)
		(fp_line
			(start 1.524 0.762)
			(end -1.524 0.762)
			(stroke
				(width 0.1524)
				(type default)
			)
			(layer "F.SilkS")
		)
		(fp_line
			(start -1.1049 -0.724916)
			(end -1.1049 0.724916)
			(stroke
				(width 0.1)
				(type default)
			)
			(layer "F.Fab")
		)
		(fp_line
			(start -1.1049 0.724916)
			(end 1.1049 0.724916)
			(stroke
				(width 0.1)
				(type default)
			)
			(layer "F.Fab")
		)
		(fp_line
			(start 1.1049 -0.724916)
			(end -1.1049 -0.724916)
			(stroke
				(width 0.1)
				(type default)
			)
			(layer "F.Fab")
		)
		(fp_line
			(start 1.1049 0.724916)
			(end 1.1049 -0.724916)
			(stroke
				(width 0.1)
				(type default)
			)
			(layer "F.Fab")
		)
		(pad "1" smd rect
			(at -0.889 0 180)
			(size 1.016 1.27)
			(layers "F.Cu" "F.Mask" "F.Paste")
			(net "GND")
		)
		(pad "2" smd rect
			(at 0.889 0 180)
			(size 1.016 1.27)
			(layers "F.Cu" "F.Mask" "F.Paste")
			(net "P3V3_AUX")
		)
	)
)
